# T6G (Grand Teton) — schematic netlist excerpt (pin names and nets, part order shuffled) for the footprints in the layout excerpt that follows; sources: Cadence DE-HDL packaged netlist, KiCad conversion of 04192023_DAF0TMB3IC0_F0TG_MB_C_brd_V02_OCP.brd

R493  Q_RES  0 5% CHIP  pkg 0402LF  page 80 : A = SMB_CPU0_4_XLTR_R_SDA ; B = SMB_CPU0_4_XLTR_SDA
R3580  Q_RES  0 5% CHIP  pkg 0402LF  page 250 : A = SMB_INA230_3V3AUX_SCL_R ; B = SMB_INA230_3V3AUX_SCL

(kicad_pcb
	(version 20260206)
	(generator "pcbnew")
	(generator_version "10.0")
	(general
		(thickness 1.6)
		(legacy_teardrops no)
	)
	(paper "A4")
	(title_block
		(title "04192023_DAF0TMB3IC0_F0TG_MB_C_brd_V02_OCP.brd")
		(comment 1 "Grand Teton / footprints 858-859 of 8354")
	)
	(layers
		(0 "F.Cu" signal "TOP")
		(4 "In1.Cu" signal "GND")
		(6 "In2.Cu" signal "IN1")
		(8 "In3.Cu" signal "GND1")
		(10 "In4.Cu" signal "IN2")
		(12 "In5.Cu" signal "GND2")
		(14 "In6.Cu" signal "IN3")
		(16 "In7.Cu" signal "GND3")
		(18 "In8.Cu" signal "VCC")
		(20 "In9.Cu" signal "VCC1")
		(22 "In10.Cu" signal "GND4")
		(24 "In11.Cu" signal "IN4")
		(26 "In12.Cu" signal "GND5")
		(28 "In13.Cu" signal "IN5")
		(30 "In14.Cu" signal "GND6")
		(32 "In15.Cu" signal "IN6")
		(34 "In16.Cu" signal "GND7")
		(2 "B.Cu" signal "BOTTOM")
		(9 "F.Adhes" user "F.Adhesive")
		(11 "B.Adhes" user "B.Adhesive")
		(13 "F.Paste" user "Package Geometry/Pastemask Top")
		(15 "B.Paste" user "Package Geometry/Pastemask Bottom")
		(5 "F.SilkS" user "Ref Des/Silkscreen Top")
		(7 "B.SilkS" user "Ref Des/Silkscreen Bottom")
		(1 "F.Mask" user "Board Geometry/Soldermask Top")
		(3 "B.Mask" user "Board Geometry/Soldermask Bottom")
		(17 "Dwgs.User" user "User.Drawings")
		(19 "Cmts.User" user "User.Comments")
		(21 "Eco1.User" user "User.Eco1")
		(23 "Eco2.User" user "User.Eco2")
		(25 "Edge.Cuts" user "Board Geometry/Outline")
		(27 "Margin" user)
		(31 "F.CrtYd" user "Package Geometry/Place Bound Top")
		(29 "B.CrtYd" user "Package Geometry/Place Bound Bottom")
		(35 "F.Fab" user "Ref Des/Assembly Top")
		(33 "B.Fab" user "Ref Des/Assembly Bottom")
	)
	(footprint ""
		(layer "F.Cu")
		(at 294.421052 -119.301514)
		(property "Reference" "R3580"
			(at 0 0 0)
			(layer "F.SilkS")
			(hide yes)
			(effects
				(font
					(size 1.27 1.27)
				)
			)
		)
		(property "Value" ""
			(at 0 0 0)
			(layer "F.Fab")
			(effects
				(font
					(size 1.27 1.27)
				)
			)
		)
		(duplicate_pad_numbers_are_jumpers no)
		(fp_line
			(start -0.7874 -0.4064)
			(end 0.7874 -0.4064)
			(stroke
				(width 0.1524)
				(type default)
			)
			(layer "F.SilkS")
		)
		(fp_line
			(start -0.7874 0.4064)
			(end -0.7874 -0.4064)
			(stroke
				(width 0.1524)
				(type default)
			)
			(layer "F.SilkS")
		)
		(fp_line
			(start 0.7874 -0.4064)
			(end 0.7874 0.4064)
			(stroke
				(width 0.1524)
				(type default)
			)
			(layer "F.SilkS")
		)
		(fp_line
			(start 0.7874 0.4064)
			(end -0.7874 0.4064)
			(stroke
				(width 0.1524)
				(type default)
			)
			(layer "F.SilkS")
		)
		(fp_line
			(start -0.67945 -0.305054)
			(end -0.12065 -0.305054)
			(stroke
				(width 0.1)
				(type default)
			)
			(layer "F.Fab")
		)
		(fp_line
			(start -0.67945 0.3048)
			(end -0.67945 -0.305054)
			(stroke
				(width 0.1)
				(type default)
			)
			(layer "F.Fab")
		)
		(fp_line
			(start -0.12065 -0.305054)
			(end -0.12065 -0.2794)
			(stroke
				(width 0.1)
				(type default)
			)
			(layer "F.Fab")
		)
		(fp_line
			(start -0.12065 -0.2794)
			(end 0.12065 -0.2794)
			(stroke
				(width 0.1)
				(type default)
			)
			(layer "F.Fab")
		)
		(fp_line
			(start -0.12065 0.2794)
			(end -0.12065 0.3048)
			(stroke
				(width 0.1)
				(type default)
			)
			(layer "F.Fab")
		)
		(fp_line
			(start -0.12065 0.3048)
			(end -0.67945 0.3048)
			(stroke
				(width 0.1)
				(type default)
			)
			(layer "F.Fab")
		)
		(fp_line
			(start 0.120396 0.2794)
			(end -0.12065 0.2794)
			(stroke
				(width 0.1)
				(type default)
			)
			(layer "F.Fab")
		)
		(fp_line
			(start 0.120396 0.3048)
			(end 0.120396 0.2794)
			(stroke
				(width 0.1)
				(type default)
			)
			(layer "F.Fab")
		)
		(fp_line
			(start 0.12065 -0.3048)
			(end 0.67945 -0.3048)
			(stroke
				(width 0.1)
				(type default)
			)
			(layer "F.Fab")
		)
		(fp_line
			(start 0.12065 -0.2794)
			(end 0.12065 -0.3048)
			(stroke
				(width 0.1)
				(type default)
			)
			(layer "F.Fab")
		)
		(fp_line
			(start 0.67945 -0.3048)
			(end 0.67945 0.3048)
			(stroke
				(width 0.1)
				(type default)
			)
			(layer "F.Fab")
		)
		(fp_line
			(start 0.67945 0.3048)
			(end 0.120396 0.3048)
			(stroke
				(width 0.1)
				(type default)
			)
			(layer "F.Fab")
		)
		(pad "1" smd circle
			(at -0.40005 0)
			(size 0 0)
			(layers "F.Cu" "F.Mask" "F.Paste")
			(net "SMB_INA230_3V3AUX_SCL_R")
		)
		(pad "2" smd circle
			(at 0.40005 0)
			(size 0 0)
			(layers "F.Cu" "F.Mask" "F.Paste")
			(net "SMB_INA230_3V3AUX_SCL")
		)
	)
	(footprint ""
		(layer "F.Cu")
		(at 176.528984 -147.086574 90)
		(property "Reference" "R493"
			(at 0 0 90)
			(layer "F.SilkS")
			(hide yes)
			(effects
				(font
					(size 1.27 1.27)
				)
			)
		)
		(property "Value" ""
			(at 0 0 90)
			(layer "F.Fab")
			(effects
				(font
					(size 1.27 1.27)
				)
			)
		)
		(duplicate_pad_numbers_are_jumpers no)
		(fp_line
			(start 0.7874 -0.4064)
			(end 0.7874 0.4064)
			(stroke
				(width 0.1524)
				(type default)
			)
			(layer "F.SilkS")
		)
		(fp_line
			(start -0.7874 -0.4064)
			(end 0.7874 -0.4064)
			(stroke
				(width 0.1524)
				(type default)
			)
			(layer "F.SilkS")
		)
		(fp_line
			(start 0.7874 0.4064)
			(end -0.7874 0.4064)
			(stroke
				(width 0.1524)
				(type default)
			)
			(layer "F.SilkS")
		)
		(fp_line
			(start -0.7874 0.4064)
			(end -0.7874 -0.4064)
			(stroke
				(width 0.1524)
				(type default)
			)
			(layer "F.SilkS")
		)
		(fp_line
			(start -0.12065 -0.305054)
			(end -0.12065 -0.2794)
			(stroke
				(width 0.1)
				(type default)
			)
			(layer "F.Fab")
		)
		(fp_line
			(start -0.67945 -0.305054)
			(end -0.12065 -0.305054)
			(stroke
				(width 0.1)
				(type default)
			)
			(layer "F.Fab")
		)
		(fp_line
			(start 0.67945 -0.3048)
			(end 0.67945 0.3048)
			(stroke
				(width 0.1)
				(type default)
			)
			(layer "F.Fab")
		)
		(fp_line
			(start 0.12065 -0.3048)
			(end 0.67945 -0.3048)
			(stroke
				(width 0.1)
				(type default)
			)
			(layer "F.Fab")
		)
		(fp_line
			(start 0.12065 -0.2794)
			(end 0.12065 -0.3048)
			(stroke
				(width 0.1)
				(type default)
			)
			(layer "F.Fab")
		)
		(fp_line
			(start -0.12065 -0.2794)
			(end 0.12065 -0.2794)
			(stroke
				(width 0.1)
				(type default)
			)
			(layer "F.Fab")
		)
		(fp_line
			(start 0.120396 0.2794)
			(end -0.12065 0.2794)
			(stroke
				(width 0.1)
				(type default)
			)
			(layer "F.Fab")
		)
		(fp_line
			(start -0.12065 0.2794)
			(end -0.12065 0.3048)
			(stroke
				(width 0.1)
				(type default)
			)
			(layer "F.Fab")
		)
		(fp_line
			(start 0.67945 0.3048)
			(end 0.120396 0.3048)
			(stroke
				(width 0.1)
				(type default)
			)
			(layer "F.Fab")
		)
		(fp_line
			(start 0.120396 0.3048)
			(end 0.120396 0.2794)
			(stroke
				(width 0.1)
				(type default)
			)
			(layer "F.Fab")
		)
		(fp_line
			(start -0.12065 0.3048)
			(end -0.67945 0.3048)
			(stroke
				(width 0.1)
				(type default)
			)
			(layer "F.Fab")
		)
		(fp_line
			(start -0.67945 0.3048)
			(end -0.67945 -0.305054)
			(stroke
				(width 0.1)
				(type default)
			)
			(layer "F.Fab")
		)
		(pad "1" smd circle
			(at -0.40005 0 90)
			(size 0 0)
			(layers "F.Cu" "F.Mask" "F.Paste")
			(net "SMB_CPU0_4_XLTR_R_SDA")
		)
		(pad "2" smd circle
			(at 0.40005 0 90)
			(size 0 0)
			(layers "F.Cu" "F.Mask" "F.Paste")
			(net "SMB_CPU0_4_XLTR_SDA")
		)
	)
)
